(kicad_pcb
	(version 20260206)
	(generator "pcbnew")
	(generator_version "10.0")
	(general
		(thickness 1.6)
		(legacy_teardrops no)
	)
	(paper "A4")
	(title_block
		(title "v1-chassis-manager — T6M_CM_d_v01_1031_1645.brd")
		(comment 1 "Open CloudServer (Microsoft) / footprint 550 of 2512 (U14), pads 1-118 of 408")
	)
	(layers
		(0 "F.Cu" signal "TOP")
		(4 "In1.Cu" signal "GND1")
		(6 "In2.Cu" signal "IN1")
		(8 "In3.Cu" signal "VCC1")
		(10 "In4.Cu" signal "VCC2")
		(12 "In5.Cu" signal "GND2")
		(14 "In6.Cu" signal "IN2")
		(16 "In7.Cu" signal "IN3")
		(18 "In8.Cu" signal "GND3")
		(2 "B.Cu" signal "BOTTOM")
		(9 "F.Adhes" user "F.Adhesive")
		(11 "B.Adhes" user "B.Adhesive")
		(13 "F.Paste" user "Package Geometry/Pastemask Top")
		(15 "B.Paste" user "Package Geometry/Pastemask Bottom")
		(5 "F.SilkS" user "Ref Des/Silkscreen Top")
		(7 "B.SilkS" user "Ref Des/Silkscreen Bottom")
		(1 "F.Mask" user "Board Geometry/Soldermask Top")
		(3 "B.Mask" user "Board Geometry/Soldermask Bottom")
		(17 "Dwgs.User" user "User.Drawings")
		(19 "Cmts.User" user "User.Comments")
		(21 "Eco1.User" user "User.Eco1")
		(23 "Eco2.User" user "User.Eco2")
		(25 "Edge.Cuts" user "Board Geometry/Outline")
		(27 "Margin" user)
		(31 "F.CrtYd" user "Package Geometry/Place Bound Top")
		(29 "B.CrtYd" user "Package Geometry/Place Bound Bottom")
		(35 "F.Fab" user "Ref Des/Assembly Top")
		(33 "B.Fab" user "Ref Des/Assembly Bottom")
	)
	(footprint ""
		(layer "F.Cu")
		(at 65.741804 -134.859522 -90)
		(property "Reference" "U14"
			(at 12.258294 13.71092 90)
			(unlocked yes)
			(layer "F.SilkS")
			(effects
				(font
					(size 1.6002 1.1938)
					(thickness 0.1524)
				)
				(justify left)
			)
		)
		(property "Value" ""
			(at 0 0 270)
			(layer "F.Fab")
			(effects
				(font
					(size 1.27 1.27)
				)
			)
		)
		(duplicate_pad_numbers_are_jumpers no)
		(pad "A1" smd circle
			(at -8.400034 -8.400034 270)
			(size 0.3683 0.3683)
			(layers "F.Cu" "F.Mask" "F.Paste")
			(net "GND")
		)
		(pad "A2" smd circle
			(at -7.599934 -8.400034 270)
			(size 0.3683 0.3683)
			(layers "F.Cu" "F.Mask" "F.Paste")
			(net "GND")
		)
		(pad "A3" smd circle
			(at -6.800088 -8.400034 270)
			(size 0.3683 0.3683)
			(layers "F.Cu" "F.Mask" "F.Paste")
			(net "GND")
		)
		(pad "A4" smd circle
			(at -5.999988 -8.400034 270)
			(size 0.3683 0.3683)
			(layers "F.Cu" "F.Mask" "F.Paste")
			(net "N3975090766")
		)
		(pad "A5" smd circle
			(at -5.199888 -8.400034 270)
			(size 0.3683 0.3683)
			(layers "F.Cu" "F.Mask" "F.Paste")
			(net "Net_1753")
		)
		(pad "A6" smd circle
			(at -4.400042 -8.400034 270)
			(size 0.3683 0.3683)
			(layers "F.Cu" "F.Mask" "F.Paste")
			(net "Net_1740")
		)
		(pad "A7" smd circle
			(at -3.599942 -8.400034 270)
			(size 0.3683 0.3683)
			(layers "F.Cu" "F.Mask" "F.Paste")
			(net "Net_1737")
		)
		(pad "A8" smd circle
			(at -2.800096 -8.400034 270)
			(size 0.3683 0.3683)
			(layers "F.Cu" "F.Mask" "F.Paste")
			(net "Net_1735")
		)
		(pad "A9" smd circle
			(at -1.999996 -8.400034 270)
			(size 0.3683 0.3683)
			(layers "F.Cu" "F.Mask" "F.Paste")
			(net "GND")
		)
		(pad "A10" smd circle
			(at -1.199896 -8.400034 270)
			(size 0.3683 0.3683)
			(layers "F.Cu" "F.Mask" "F.Paste")
			(net "Net_1762")
		)
		(pad "A11" smd circle
			(at -0.40005 -8.400034 270)
			(size 0.3683 0.3683)
			(layers "F.Cu" "F.Mask" "F.Paste")
			(net "GND")
		)
		(pad "A12" smd circle
			(at 0.40005 -8.400034 270)
			(size 0.3683 0.3683)
			(layers "F.Cu" "F.Mask" "F.Paste")
			(net "Net_1754")
		)
		(pad "A13" smd circle
			(at 1.199896 -8.400034 270)
			(size 0.3683 0.3683)
			(layers "F.Cu" "F.Mask" "F.Paste")
			(net "Net_1759")
		)
		(pad "A14" smd circle
			(at 1.999996 -8.400034 270)
			(size 0.3683 0.3683)
			(layers "F.Cu" "F.Mask" "F.Paste")
			(net "Net_510")
		)
		(pad "A15" smd circle
			(at 2.800096 -8.400034 270)
			(size 0.3683 0.3683)
			(layers "F.Cu" "F.Mask" "F.Paste")
			(net "Net_1723")
		)
		(pad "A16" smd circle
			(at 3.599942 -8.400034 270)
			(size 0.3683 0.3683)
			(layers "F.Cu" "F.Mask" "F.Paste")
			(net "Net_1719")
		)
		(pad "A17" smd circle
			(at 4.400042 -8.400034 270)
			(size 0.3683 0.3683)
			(layers "F.Cu" "F.Mask" "F.Paste")
			(net "Net_1716")
		)
		(pad "A18" smd circle
			(at 5.199888 -8.400034 270)
			(size 0.3683 0.3683)
			(layers "F.Cu" "F.Mask" "F.Paste")
			(net "Net_564")
		)
		(pad "A19" smd circle
			(at 5.999988 -8.400034 270)
			(size 0.3683 0.3683)
			(layers "F.Cu" "F.Mask" "F.Paste")
			(net "Net_1732")
		)
		(pad "A20" smd circle
			(at 6.800088 -8.400034 270)
			(size 0.3683 0.3683)
			(layers "F.Cu" "F.Mask" "F.Paste")
			(net "Net_1730")
		)
		(pad "A21" smd circle
			(at 7.599934 -8.400034 270)
			(size 0.3683 0.3683)
			(layers "F.Cu" "F.Mask" "F.Paste")
			(net "PD_BMC_LPC")
		)
		(pad "A22" smd circle
			(at 8.400034 -8.400034 270)
			(size 0.3683 0.3683)
			(layers "F.Cu" "F.Mask" "F.Paste")
			(net "PD_BMC_LPC")
		)
		(pad "AA1" smd circle
			(at -8.400034 7.599934 270)
			(size 0.3683 0.3683)
			(layers "F.Cu" "F.Mask" "F.Paste")
			(net "Net_476")
		)
		(pad "AA2" smd circle
			(at -7.599934 7.599934 270)
			(size 0.3683 0.3683)
			(layers "F.Cu" "F.Mask" "F.Paste")
			(net "Net_542")
		)
		(pad "AA3" smd circle
			(at -6.800088 7.599934 270)
			(size 0.3683 0.3683)
			(layers "F.Cu" "F.Mask" "F.Paste")
			(net "Net_1776")
		)
		(pad "AA4" smd circle
			(at -5.999988 7.599934 270)
			(size 0.3683 0.3683)
			(layers "F.Cu" "F.Mask" "F.Paste")
			(net "Net_1779")
		)
		(pad "AA5" smd circle
			(at -5.199888 7.599934 270)
			(size 0.3683 0.3683)
			(layers "F.Cu" "F.Mask" "F.Paste")
			(net "Net_1780")
		)
		(pad "AA6" smd circle
			(at -4.400042 7.599934 270)
			(size 0.3683 0.3683)
			(layers "F.Cu" "F.Mask" "F.Paste")
			(net "Net_544")
		)
		(pad "AA7" smd circle
			(at -3.599942 7.599934 270)
			(size 0.3683 0.3683)
			(layers "F.Cu" "F.Mask" "F.Paste")
			(net "Net_505")
		)
		(pad "AA8" smd circle
			(at -2.800096 7.599934 270)
			(size 0.3683 0.3683)
			(layers "F.Cu" "F.Mask" "F.Paste")
			(net "BMC_NODE1_DDR_DQS1_DP")
		)
		(pad "AA9" smd circle
			(at -1.999996 7.599934 270)
			(size 0.3683 0.3683)
			(layers "F.Cu" "F.Mask" "F.Paste")
			(net "BMC_NODE1_DDR_D10")
		)
		(pad "AA10" smd circle
			(at -1.199896 7.599934 270)
			(size 0.3683 0.3683)
			(layers "F.Cu" "F.Mask" "F.Paste")
			(net "BMC_NODE1_DDR_DQS0_DN")
		)
		(pad "AA11" smd circle
			(at -0.40005 7.599934 270)
			(size 0.3683 0.3683)
			(layers "F.Cu" "F.Mask" "F.Paste")
			(net "BMC_NODE1_DDR_D3")
		)
		(pad "AA12" smd circle
			(at 0.40005 7.599934 270)
			(size 0.3683 0.3683)
			(layers "F.Cu" "F.Mask" "F.Paste")
			(net "BMC_NODE1_DDR_CLK_DN")
		)
		(pad "AA13" smd circle
			(at 1.199896 7.599934 270)
			(size 0.3683 0.3683)
			(layers "F.Cu" "F.Mask" "F.Paste")
			(net "BMC_NODE1_DDR_CS_L")
		)
		(pad "AA14" smd circle
			(at 1.999996 7.599934 270)
			(size 0.3683 0.3683)
			(layers "F.Cu" "F.Mask" "F.Paste")
			(net "BMC_NODE1_DDR_BA1")
		)
		(pad "AA15" smd circle
			(at 2.800096 7.599934 270)
			(size 0.3683 0.3683)
			(layers "F.Cu" "F.Mask" "F.Paste")
			(net "BMC_NODE1_DDR_MA6")
		)
		(pad "AA16" smd circle
			(at 3.599942 7.599934 270)
			(size 0.3683 0.3683)
			(layers "F.Cu" "F.Mask" "F.Paste")
			(net "BMC_NODE1_DDR_MA11")
		)
		(pad "AA17" smd circle
			(at 4.400042 7.599934 270)
			(size 0.3683 0.3683)
			(layers "F.Cu" "F.Mask" "F.Paste")
			(net "BMC_NODE1_DDR_MA9")
		)
		(pad "AA18" smd circle
			(at 5.199888 7.599934 270)
			(size 0.3683 0.3683)
			(layers "F.Cu" "F.Mask" "F.Paste")
			(net "GND")
		)
		(pad "AA19" smd circle
			(at 5.999988 7.599934 270)
			(size 0.3683 0.3683)
			(layers "F.Cu" "F.Mask" "F.Paste")
			(net "GND")
		)
		(pad "AA20" smd circle
			(at 6.800088 7.599934 270)
			(size 0.3683 0.3683)
			(layers "F.Cu" "F.Mask" "F.Paste")
			(net "BMC_NODE1_USBVREF")
		)
		(pad "AA21" smd circle
			(at 7.599934 7.599934 270)
			(size 0.3683 0.3683)
			(layers "F.Cu" "F.Mask" "F.Paste")
			(net "Net_531")
		)
		(pad "AA22" smd circle
			(at 8.400034 7.599934 270)
			(size 0.3683 0.3683)
			(layers "F.Cu" "F.Mask" "F.Paste")
			(net "Net_1770")
		)
		(pad "AB1" smd circle
			(at -8.400034 8.400034 270)
			(size 0.3683 0.3683)
			(layers "F.Cu" "F.Mask" "F.Paste")
			(net "Net_541")
		)
		(pad "AB2" smd circle
			(at -7.599934 8.400034 270)
			(size 0.3683 0.3683)
			(layers "F.Cu" "F.Mask" "F.Paste")
			(net "Net_1777")
		)
		(pad "AB3" smd circle
			(at -6.800088 8.400034 270)
			(size 0.3683 0.3683)
			(layers "F.Cu" "F.Mask" "F.Paste")
			(net "Net_540")
		)
		(pad "AB4" smd circle
			(at -5.999988 8.400034 270)
			(size 0.3683 0.3683)
			(layers "F.Cu" "F.Mask" "F.Paste")
			(net "Net_543")
		)
		(pad "AB5" smd circle
			(at -5.199888 8.400034 270)
			(size 0.3683 0.3683)
			(layers "F.Cu" "F.Mask" "F.Paste")
			(net "Net_1783")
		)
		(pad "AB6" smd circle
			(at -4.400042 8.400034 270)
			(size 0.3683 0.3683)
			(layers "F.Cu" "F.Mask" "F.Paste")
			(net "Net_507")
		)
		(pad "AB7" smd circle
			(at -3.599942 8.400034 270)
			(size 0.3683 0.3683)
			(layers "F.Cu" "F.Mask" "F.Paste")
			(net "Net_545")
		)
		(pad "AB8" smd circle
			(at -2.800096 8.400034 270)
			(size 0.3683 0.3683)
			(layers "F.Cu" "F.Mask" "F.Paste")
			(net "BMC_NODE1_DDR_DQS1_DN")
		)
		(pad "AB9" smd circle
			(at -1.999996 8.400034 270)
			(size 0.3683 0.3683)
			(layers "F.Cu" "F.Mask" "F.Paste")
			(net "BMC_NODE1_DDR_D9")
		)
		(pad "AB10" smd circle
			(at -1.199896 8.400034 270)
			(size 0.3683 0.3683)
			(layers "F.Cu" "F.Mask" "F.Paste")
			(net "BMC_NODE1_DDR_DQS0_DP")
		)
		(pad "AB11" smd circle
			(at -0.40005 8.400034 270)
			(size 0.3683 0.3683)
			(layers "F.Cu" "F.Mask" "F.Paste")
			(net "BMC_NODE1_DDR_D2")
		)
		(pad "AB12" smd circle
			(at 0.40005 8.400034 270)
			(size 0.3683 0.3683)
			(layers "F.Cu" "F.Mask" "F.Paste")
			(net "BMC_NODE1_DDR_CLK_DP")
		)
		(pad "AB13" smd circle
			(at 1.199896 8.400034 270)
			(size 0.3683 0.3683)
			(layers "F.Cu" "F.Mask" "F.Paste")
			(net "BMC_NODE1_DDR_CAS_L")
		)
		(pad "AB14" smd circle
			(at 1.999996 8.400034 270)
			(size 0.3683 0.3683)
			(layers "F.Cu" "F.Mask" "F.Paste")
			(net "BMC_NODE1_DDR_MA0")
		)
		(pad "AB15" smd circle
			(at 2.800096 8.400034 270)
			(size 0.3683 0.3683)
			(layers "F.Cu" "F.Mask" "F.Paste")
			(net "BMC_NODE1_DDR_MA4")
		)
		(pad "AB16" smd circle
			(at 3.599942 8.400034 270)
			(size 0.3683 0.3683)
			(layers "F.Cu" "F.Mask" "F.Paste")
			(net "BMC_NODE1_DDR_MA8")
		)
		(pad "AB17" smd circle
			(at 4.400042 8.400034 270)
			(size 0.3683 0.3683)
			(layers "F.Cu" "F.Mask" "F.Paste")
			(net "BMC_NODE1_DDR_MA14")
		)
		(pad "AB18" smd circle
			(at 5.199888 8.400034 270)
			(size 0.3683 0.3683)
			(layers "F.Cu" "F.Mask" "F.Paste")
			(net "BMC_NODE1_DDR_MA7")
		)
		(pad "AB19" smd circle
			(at 5.999988 8.400034 270)
			(size 0.3683 0.3683)
			(layers "F.Cu" "F.Mask" "F.Paste")
			(net "BMC_NODE1_MPLLAV33")
		)
		(pad "AB20" smd circle
			(at 6.800088 8.400034 270)
			(size 0.3683 0.3683)
			(layers "F.Cu" "F.Mask" "F.Paste")
			(net "Net_520")
		)
		(pad "AB21" smd circle
			(at 7.599934 8.400034 270)
			(size 0.3683 0.3683)
			(layers "F.Cu" "F.Mask" "F.Paste")
			(net "Net_521")
		)
		(pad "AB22" smd circle
			(at 8.400034 8.400034 270)
			(size 0.3683 0.3683)
			(layers "F.Cu" "F.Mask" "F.Paste")
			(net "BMC_NODE1_CLK_24M")
		)
		(pad "B1" smd circle
			(at -8.400034 -7.599934 270)
			(size 0.3683 0.3683)
			(layers "F.Cu" "F.Mask" "F.Paste")
			(net "GND")
		)
		(pad "B2" smd circle
			(at -7.599934 -7.599934 270)
			(size 0.3683 0.3683)
			(layers "F.Cu" "F.Mask" "F.Paste")
			(net "GND")
		)
		(pad "B3" smd circle
			(at -6.800088 -7.599934 270)
			(size 0.3683 0.3683)
			(layers "F.Cu" "F.Mask" "F.Paste")
			(net "GND")
		)
		(pad "B4" smd circle
			(at -5.999988 -7.599934 270)
			(size 0.3683 0.3683)
			(layers "F.Cu" "F.Mask" "F.Paste")
			(net "GND")
		)
		(pad "B5" smd circle
			(at -5.199888 -7.599934 270)
			(size 0.3683 0.3683)
			(layers "F.Cu" "F.Mask" "F.Paste")
			(net "N3975090765")
		)
		(pad "B6" smd circle
			(at -4.400042 -7.599934 270)
			(size 0.3683 0.3683)
			(layers "F.Cu" "F.Mask" "F.Paste")
			(net "Net_1739")
		)
		(pad "B7" smd circle
			(at -3.599942 -7.599934 270)
			(size 0.3683 0.3683)
			(layers "F.Cu" "F.Mask" "F.Paste")
			(net "Net_1736")
		)
		(pad "B8" smd circle
			(at -2.800096 -7.599934 270)
			(size 0.3683 0.3683)
			(layers "F.Cu" "F.Mask" "F.Paste")
			(net "GND")
		)
		(pad "B9" smd circle
			(at -1.999996 -7.599934 270)
			(size 0.3683 0.3683)
			(layers "F.Cu" "F.Mask" "F.Paste")
			(net "GND")
		)
		(pad "B10" smd circle
			(at -1.199896 -7.599934 270)
			(size 0.3683 0.3683)
			(layers "F.Cu" "F.Mask" "F.Paste")
			(net "Net_1763")
		)
		(pad "B11" smd circle
			(at -0.40005 -7.599934 270)
			(size 0.3683 0.3683)
			(layers "F.Cu" "F.Mask" "F.Paste")
			(net "GND")
		)
		(pad "B12" smd circle
			(at 0.40005 -7.599934 270)
			(size 0.3683 0.3683)
			(layers "F.Cu" "F.Mask" "F.Paste")
			(net "Net_1755")
		)
		(pad "B13" smd circle
			(at 1.199896 -7.599934 270)
			(size 0.3683 0.3683)
			(layers "F.Cu" "F.Mask" "F.Paste")
			(net "Net_1768")
		)
		(pad "B14" smd circle
			(at 1.999996 -7.599934 270)
			(size 0.3683 0.3683)
			(layers "F.Cu" "F.Mask" "F.Paste")
			(net "Net_1727")
		)
		(pad "B15" smd circle
			(at 2.800096 -7.599934 270)
			(size 0.3683 0.3683)
			(layers "F.Cu" "F.Mask" "F.Paste")
			(net "Net_1722")
		)
		(pad "B16" smd circle
			(at 3.599942 -7.599934 270)
			(size 0.3683 0.3683)
			(layers "F.Cu" "F.Mask" "F.Paste")
			(net "Net_1718")
		)
		(pad "B17" smd circle
			(at 4.400042 -7.599934 270)
			(size 0.3683 0.3683)
			(layers "F.Cu" "F.Mask" "F.Paste")
			(net "Net_1715")
		)
		(pad "B18" smd circle
			(at 5.199888 -7.599934 270)
			(size 0.3683 0.3683)
			(layers "F.Cu" "F.Mask" "F.Paste")
			(net "Net_1731")
		)
		(pad "B19" smd circle
			(at 5.999988 -7.599934 270)
			(size 0.3683 0.3683)
			(layers "F.Cu" "F.Mask" "F.Paste")
			(net "Net_1729")
		)
		(pad "B20" smd circle
			(at 6.800088 -7.599934 270)
			(size 0.3683 0.3683)
			(layers "F.Cu" "F.Mask" "F.Paste")
			(net "LPC_CLK_AST")
		)
		(pad "B21" smd circle
			(at 7.599934 -7.599934 270)
			(size 0.3683 0.3683)
			(layers "F.Cu" "F.Mask" "F.Paste")
			(net "PD_BMC_LPC")
		)
		(pad "B22" smd circle
			(at 8.400034 -7.599934 270)
			(size 0.3683 0.3683)
			(layers "F.Cu" "F.Mask" "F.Paste")
			(net "Net_1744")
		)
		(pad "C1" smd circle
			(at -8.400034 -6.800088 270)
			(size 0.3683 0.3683)
			(layers "F.Cu" "F.Mask" "F.Paste")
			(net "GND")
		)
		(pad "C2" smd circle
			(at -7.599934 -6.800088 270)
			(size 0.3683 0.3683)
			(layers "F.Cu" "F.Mask" "F.Paste")
			(net "GND")
		)
		(pad "C3" smd circle
			(at -6.800088 -6.800088 270)
			(size 0.3683 0.3683)
			(layers "F.Cu" "F.Mask" "F.Paste")
			(net "GND")
		)
		(pad "C4" smd circle
			(at -5.999988 -6.800088 270)
			(size 0.3683 0.3683)
			(layers "F.Cu" "F.Mask" "F.Paste")
			(net "GND")
		)
		(pad "C5" smd circle
			(at -5.199888 -6.800088 270)
			(size 0.3683 0.3683)
			(layers "F.Cu" "F.Mask" "F.Paste")
			(net "GND")
		)
		(pad "C6" smd circle
			(at -4.400042 -6.800088 270)
			(size 0.3683 0.3683)
			(layers "F.Cu" "F.Mask" "F.Paste")
			(net "Net_1752")
		)
		(pad "C7" smd circle
			(at -3.599942 -6.800088 270)
			(size 0.3683 0.3683)
			(layers "F.Cu" "F.Mask" "F.Paste")
			(net "Net_538")
		)
		(pad "C8" smd circle
			(at -2.800096 -6.800088 270)
			(size 0.3683 0.3683)
			(layers "F.Cu" "F.Mask" "F.Paste")
			(net "GND")
		)
		(pad "C9" smd circle
			(at -1.999996 -6.800088 270)
			(size 0.3683 0.3683)
			(layers "F.Cu" "F.Mask" "F.Paste")
			(net "GND")
		)
		(pad "C10" smd circle
			(at -1.199896 -6.800088 270)
			(size 0.3683 0.3683)
			(layers "F.Cu" "F.Mask" "F.Paste")
			(net "Net_1764")
		)
		(pad "C11" smd circle
			(at -0.40005 -6.800088 270)
			(size 0.3683 0.3683)
			(layers "F.Cu" "F.Mask" "F.Paste")
			(net "GND")
		)
		(pad "C12" smd circle
			(at 0.40005 -6.800088 270)
			(size 0.3683 0.3683)
			(layers "F.Cu" "F.Mask" "F.Paste")
			(net "Net_1756")
		)
		(pad "C13" smd circle
			(at 1.199896 -6.800088 270)
			(size 0.3683 0.3683)
			(layers "F.Cu" "F.Mask" "F.Paste")
			(net "Net_1767")
		)
		(pad "C14" smd circle
			(at 1.999996 -6.800088 270)
			(size 0.3683 0.3683)
			(layers "F.Cu" "F.Mask" "F.Paste")
			(net "Net_1726")
		)
		(pad "C15" smd circle
			(at 2.800096 -6.800088 270)
			(size 0.3683 0.3683)
			(layers "F.Cu" "F.Mask" "F.Paste")
			(net "Net_469")
		)
		(pad "C16" smd circle
			(at 3.599942 -6.800088 270)
			(size 0.3683 0.3683)
			(layers "F.Cu" "F.Mask" "F.Paste")
			(net "Net_1717")
		)
		(pad "C17" smd circle
			(at 4.400042 -6.800088 270)
			(size 0.3683 0.3683)
			(layers "F.Cu" "F.Mask" "F.Paste")
			(net "Net_1734")
		)
		(pad "C18" smd circle
			(at 5.199888 -6.800088 270)
			(size 0.3683 0.3683)
			(layers "F.Cu" "F.Mask" "F.Paste")
			(net "Net_1746")
		)
		(pad "C19" smd circle
			(at 5.999988 -6.800088 270)
			(size 0.3683 0.3683)
			(layers "F.Cu" "F.Mask" "F.Paste")
			(net "PD_BMC_LPC")
		)
		(pad "C20" smd circle
			(at 6.800088 -6.800088 270)
			(size 0.3683 0.3683)
			(layers "F.Cu" "F.Mask" "F.Paste")
			(net "Net_539")
		)
		(pad "C21" smd circle
			(at 7.599934 -6.800088 270)
			(size 0.3683 0.3683)
			(layers "F.Cu" "F.Mask" "F.Paste")
			(net "BMC_NODE1_VCC_1V8_PCIEA")
		)
		(pad "C22" smd circle
			(at 8.400034 -6.800088 270)
			(size 0.3683 0.3683)
			(layers "F.Cu" "F.Mask" "F.Paste")
			(net "Net_537")
		)
		(pad "D1" smd circle
			(at -8.400034 -5.999988 270)
			(size 0.3683 0.3683)
			(layers "F.Cu" "F.Mask" "F.Paste")
			(net "GND")
		)
		(pad "D2" smd circle
			(at -7.599934 -5.999988 270)
			(size 0.3683 0.3683)
			(layers "F.Cu" "F.Mask" "F.Paste")
			(net "GND")
		)
		(pad "D3" smd circle
			(at -6.800088 -5.999988 270)
			(size 0.3683 0.3683)
			(layers "F.Cu" "F.Mask" "F.Paste")
			(net "GND")
		)
		(pad "D4" smd circle
			(at -5.999988 -5.999988 270)
			(size 0.3683 0.3683)
			(layers "F.Cu" "F.Mask" "F.Paste")
			(net "GND")
		)
		(pad "D5" smd circle
			(at -5.199888 -5.999988 270)
			(size 0.3683 0.3683)
			(layers "F.Cu" "F.Mask" "F.Paste")
			(net "GND")
		)
		(pad "D6" smd circle
			(at -4.400042 -5.999988 270)
			(size 0.3683 0.3683)
			(layers "F.Cu" "F.Mask" "F.Paste")
			(net "Net_1766")
		)
		(pad "D7" smd circle
			(at -3.599942 -5.999988 270)
			(size 0.3683 0.3683)
			(layers "F.Cu" "F.Mask" "F.Paste")
			(net "Net_1738")
		)
		(pad "D8" smd circle
			(at -2.800096 -5.999988 270)
			(size 0.3683 0.3683)
			(layers "F.Cu" "F.Mask" "F.Paste")
			(net "GND")
		)
	)
)
